(kicad_pcb
	(version 20260206)
	(generator "pcbnew")
	(generator_version "10.0")
	(general
		(thickness 1.6)
		(legacy_teardrops no)
	)
	(paper "A4")
	(title_block
		(title "netronome-mezz — pcbd0082-001_rev01_jul9_a.brd")
		(comment 1 "Open CloudServer (Microsoft) / footprint 225 of 714 (U1), pads 119-233 of 1022")
	)
	(layers
		(0 "F.Cu" signal "TOP")
		(4 "In1.Cu" signal "02_GND")
		(6 "In2.Cu" signal "03_SIG")
		(8 "In3.Cu" signal "04_SIG")
		(10 "In4.Cu" signal "05_GND")
		(12 "In5.Cu" signal "06_PWR1")
		(14 "In6.Cu" signal "07_SIG")
		(16 "In7.Cu" signal "08_SIG")
		(18 "In8.Cu" signal "09_GND")
		(2 "B.Cu" signal "BOTTOM")
		(9 "F.Adhes" user "F.Adhesive")
		(11 "B.Adhes" user "B.Adhesive")
		(13 "F.Paste" user "Package Geometry/Pastemask Top")
		(15 "B.Paste" user "Package Geometry/Pastemask Bottom")
		(5 "F.SilkS" user "Ref Des/Silkscreen Top")
		(7 "B.SilkS" user "Ref Des/Silkscreen Bottom")
		(1 "F.Mask" user "Board Geometry/Soldermask Top")
		(3 "B.Mask" user "Board Geometry/Soldermask Bottom")
		(17 "Dwgs.User" user "User.Drawings")
		(19 "Cmts.User" user "User.Comments")
		(21 "Eco1.User" user "User.Eco1")
		(23 "Eco2.User" user "User.Eco2")
		(25 "Edge.Cuts" user "Board Geometry/Outline")
		(27 "Margin" user)
		(31 "F.CrtYd" user "Package Geometry/Place Bound Top")
		(29 "B.CrtYd" user "Package Geometry/Place Bound Bottom")
		(35 "F.Fab" user "Ref Des/Assembly Top")
		(33 "B.Fab" user "Ref Des/Assembly Bottom")
		(45 "User.4" user "COMPVAL_TYPE_BOTTOM")
	)
	(footprint ""
		(layer "F.Cu")
		(at 54.737 18.542 180)
		(property "Reference" "U1"
			(at -12.192 17.9705 0)
			(unlocked yes)
			(layer "F.SilkS")
			(effects
				(font
					(size 1.27 0.9652)
					(thickness 0.1524)
				)
				(justify left)
			)
		)
		(property "Value" "*"
			(at -0.4826 1.74879 180)
			(unlocked yes)
			(layer "F.Fab")
			(hide yes)
			(effects
				(font
					(size 1.27 0.9652)
					(thickness 0.000001)
				)
				(justify left)
			)
		)
		(property "Device Type" "ICBG0048"
			(at -0.4826 1.74879 180)
			(unlocked yes)
			(layer "F.Fab")
			(hide yes)
			(effects
				(font
					(size 1.27 0.9652)
					(thickness 0.000001)
				)
				(justify left)
			)
		)
		(duplicate_pad_numbers_are_jumpers no)
		(pad "AC23" smd circle
			(at 6.500012 6.500012 180)
			(size 0.508 0.508)
			(layers "F.Cu" "F.Mask" "F.Paste")
			(net "VDD_CORE")
		)
		(pad "AC24" smd circle
			(at 7.50001 6.500012 180)
			(size 0.508 0.508)
			(layers "F.Cu" "F.Mask" "F.Paste")
			(net "NFP_VDD_CORE_SENSE_VSS")
		)
		(pad "AC25" smd circle
			(at 8.500008 6.500012 180)
			(size 0.508 0.508)
			(layers "F.Cu" "F.Mask" "F.Paste")
			(net "NFP_VDD_CORE_SENSE_VDD")
		)
		(pad "AC26" smd circle
			(at 9.500006 6.500012 180)
			(size 0.508 0.508)
			(layers "F.Cu" "F.Mask" "F.Paste")
			(net "GND")
		)
		(pad "AC27" smd circle
			(at 10.500004 6.500012 180)
			(size 0.508 0.508)
			(layers "F.Cu" "F.Mask" "F.Paste")
			(net "NFP_CPLD_PRGM_JTAG_TDI")
		)
		(pad "AC28" smd circle
			(at 11.500002 6.500012 180)
			(size 0.508 0.508)
			(layers "F.Cu" "F.Mask" "F.Paste")
			(net "NFP_CPLD_PRGM_JTAG_TDO")
		)
		(pad "AC29" smd circle
			(at 12.5 6.500012 180)
			(size 0.508 0.508)
			(layers "F.Cu" "F.Mask" "F.Paste")
			(net "GND")
		)
		(pad "AC30" smd circle
			(at 13.499998 6.500012 180)
			(size 0.508 0.508)
			(layers "F.Cu" "F.Mask" "F.Paste")
			(net "NFP_CPLD_PRGM_JTAG_TMS")
		)
		(pad "AC31" smd circle
			(at 14.499996 6.500012 180)
			(size 0.508 0.508)
			(layers "F.Cu" "F.Mask" "F.Paste")
			(net "PGRM_JTAG_TMS")
		)
		(pad "AC32" smd circle
			(at 15.499994 6.500012 180)
			(size 0.508 0.508)
			(layers "F.Cu" "F.Mask" "F.Paste")
			(net "_PGRM_JTAG_TDO")
		)
		(pad "AD1" smd circle
			(at -15.499994 7.50001 180)
			(size 0.508 0.508)
			(layers "F.Cu" "F.Mask" "F.Paste")
			(net "DDR0_32A_DQ3")
		)
		(pad "AD2" smd circle
			(at -14.499996 7.50001 180)
			(size 0.508 0.508)
			(layers "F.Cu" "F.Mask" "F.Paste")
			(net "DDR0_32A_DQ9")
		)
		(pad "AD3" smd circle
			(at -13.499998 7.50001 180)
			(size 0.508 0.508)
			(layers "F.Cu" "F.Mask" "F.Paste")
			(net "DDR0_32A_DM1")
		)
		(pad "AD4" smd circle
			(at -12.5 7.50001 180)
			(size 0.508 0.508)
			(layers "F.Cu" "F.Mask" "F.Paste")
			(net "DDR0_32A_DQ14")
		)
		(pad "AD5" smd circle
			(at -11.500002 7.50001 180)
			(size 0.508 0.508)
			(layers "F.Cu" "F.Mask" "F.Paste")
			(net "DDR0_32A_DQ15")
		)
		(pad "AD6" smd circle
			(at -10.500004 7.50001 180)
			(size 0.508 0.508)
			(layers "F.Cu" "F.Mask" "F.Paste")
			(net "DDR0_32A_BA2")
		)
		(pad "AD7" smd circle
			(at -9.500006 7.50001 180)
			(size 0.508 0.508)
			(layers "F.Cu" "F.Mask" "F.Paste")
			(net "DDR0_32A_A6")
		)
		(pad "AD8" smd circle
			(at -8.500008 7.50001 180)
			(size 0.508 0.508)
			(layers "F.Cu" "F.Mask" "F.Paste")
			(net "DDR0_32A_A0")
		)
		(pad "AD9" smd circle
			(at -7.50001 7.50001 180)
			(size 0.508 0.508)
			(layers "F.Cu" "F.Mask" "F.Paste")
			(net "DDR0_32A_A2")
		)
		(pad "AD10" smd circle
			(at -6.500012 7.50001 180)
			(size 0.508 0.508)
			(layers "F.Cu" "F.Mask" "F.Paste")
			(net "GND")
		)
		(pad "AD11" smd circle
			(at -5.499989 7.50001 180)
			(size 0.508 0.508)
			(layers "F.Cu" "F.Mask" "F.Paste")
			(net "GND")
		)
		(pad "AD12" smd circle
			(at -4.499991 7.50001 180)
			(size 0.508 0.508)
			(layers "F.Cu" "F.Mask" "F.Paste")
			(net "VDD_CORE")
		)
		(pad "AD13" smd circle
			(at -3.499993 7.50001 180)
			(size 0.508 0.508)
			(layers "F.Cu" "F.Mask" "F.Paste")
			(net "GND")
		)
		(pad "AD14" smd circle
			(at -2.499995 7.50001 180)
			(size 0.508 0.508)
			(layers "F.Cu" "F.Mask" "F.Paste")
			(net "VDD_CORE")
		)
		(pad "AD15" smd circle
			(at -1.499997 7.50001 180)
			(size 0.508 0.508)
			(layers "F.Cu" "F.Mask" "F.Paste")
			(net "GND")
		)
		(pad "AD16" smd circle
			(at -0.499999 7.50001 180)
			(size 0.508 0.508)
			(layers "F.Cu" "F.Mask" "F.Paste")
			(net "VDD_CORE")
		)
		(pad "AD17" smd circle
			(at 0.499999 7.50001 180)
			(size 0.508 0.508)
			(layers "F.Cu" "F.Mask" "F.Paste")
			(net "GND")
		)
		(pad "AD18" smd circle
			(at 1.499997 7.50001 180)
			(size 0.508 0.508)
			(layers "F.Cu" "F.Mask" "F.Paste")
			(net "VDD_CORE")
		)
		(pad "AD19" smd circle
			(at 2.499995 7.50001 180)
			(size 0.508 0.508)
			(layers "F.Cu" "F.Mask" "F.Paste")
			(net "GND")
		)
		(pad "AD20" smd circle
			(at 3.499993 7.50001 180)
			(size 0.508 0.508)
			(layers "F.Cu" "F.Mask" "F.Paste")
			(net "VDD_CORE")
		)
		(pad "AD21" smd circle
			(at 4.499991 7.50001 180)
			(size 0.508 0.508)
			(layers "F.Cu" "F.Mask" "F.Paste")
			(net "GND")
		)
		(pad "AD22" smd circle
			(at 5.499989 7.50001 180)
			(size 0.508 0.508)
			(layers "F.Cu" "F.Mask" "F.Paste")
			(net "VDD_CORE")
		)
		(pad "AD23" smd circle
			(at 6.500012 7.50001 180)
			(size 0.508 0.508)
			(layers "F.Cu" "F.Mask" "F.Paste")
			(net "GND")
		)
		(pad "AD24" smd circle
			(at 7.50001 7.50001 180)
			(size 0.508 0.508)
			(layers "F.Cu" "F.Mask" "F.Paste")
			(net "VDD_CORE")
		)
		(pad "AD25" smd circle
			(at 8.500008 7.50001 180)
			(size 0.508 0.508)
			(layers "F.Cu" "F.Mask" "F.Paste")
			(net "GND")
		)
		(pad "AD26" smd circle
			(at 9.500006 7.50001 180)
			(size 0.508 0.508)
			(layers "F.Cu" "F.Mask" "F.Paste")
			(net "VDD_CORE")
		)
		(pad "AD27" smd circle
			(at 10.500004 7.50001 180)
			(size 0.508 0.508)
			(layers "F.Cu" "F.Mask" "F.Paste")
			(net "VDD_3.3V")
		)
		(pad "AD28" smd circle
			(at 11.500002 7.50001 180)
			(size 0.508 0.508)
			(layers "F.Cu" "F.Mask" "F.Paste")
			(net "NFP_CPLD_PRGM_JTAG_TCK")
		)
		(pad "AD29" smd circle
			(at 12.5 7.50001 180)
			(size 0.508 0.508)
			(layers "F.Cu" "F.Mask" "F.Paste")
			(net "MUX_NFP_SMBUS_SCL")
		)
		(pad "AD30" smd circle
			(at 13.499998 7.50001 180)
			(size 0.508 0.508)
			(layers "F.Cu" "F.Mask" "F.Paste")
			(net "MUX_NFP_SMBUS_ALERT_L")
		)
		(pad "AD31" smd circle
			(at 14.499996 7.50001 180)
			(size 0.508 0.508)
			(layers "F.Cu" "F.Mask" "F.Paste")
			(net "GND")
		)
		(pad "AD32" smd circle
			(at 15.499994 7.50001 180)
			(size 0.508 0.508)
			(layers "F.Cu" "F.Mask" "F.Paste")
			(net "PGRM_JTAG_TDI")
		)
		(pad "AE1" smd circle
			(at -15.499994 8.500008 180)
			(size 0.508 0.508)
			(layers "F.Cu" "F.Mask" "F.Paste")
			(net "DDR0_32A_DQS0_N")
		)
		(pad "AE2" smd circle
			(at -14.499996 8.500008 180)
			(size 0.508 0.508)
			(layers "F.Cu" "F.Mask" "F.Paste")
			(net "DDR0_32A_DQ2")
		)
		(pad "AE3" smd circle
			(at -13.499998 8.500008 180)
			(size 0.508 0.508)
			(layers "F.Cu" "F.Mask" "F.Paste")
			(net "DDR0_32A_DQ1")
		)
		(pad "AE4" smd circle
			(at -12.5 8.500008 180)
			(size 0.508 0.508)
			(layers "F.Cu" "F.Mask" "F.Paste")
			(net "DDR0_32A_DQ5")
		)
		(pad "AE5" smd circle
			(at -11.500002 8.500008 180)
			(size 0.508 0.508)
			(layers "F.Cu" "F.Mask" "F.Paste")
			(net "DDR0_32A_DQ0")
		)
		(pad "AE6" smd circle
			(at -10.500004 8.500008 180)
			(size 0.508 0.508)
			(layers "F.Cu" "F.Mask" "F.Paste")
			(net "DDR0_32A_A9")
		)
		(pad "AE7" smd circle
			(at -9.500006 8.500008 180)
			(size 0.508 0.508)
			(layers "F.Cu" "F.Mask" "F.Paste")
			(net "DDR0_32A_A8")
		)
		(pad "AE8" smd circle
			(at -8.500008 8.500008 180)
			(size 0.508 0.508)
			(layers "F.Cu" "F.Mask" "F.Paste")
			(net "DDR0_32A_A13")
		)
		(pad "AE9" smd circle
			(at -7.50001 8.500008 180)
			(size 0.508 0.508)
			(layers "F.Cu" "F.Mask" "F.Paste")
			(net "DDR_VDDQ")
		)
		(pad "AE10" smd circle
			(at -6.500012 8.500008 180)
			(size 0.508 0.508)
			(layers "F.Cu" "F.Mask" "F.Paste")
			(net "GND")
		)
		(pad "AE11" smd circle
			(at -5.499989 8.500008 180)
			(size 0.508 0.508)
			(layers "F.Cu" "F.Mask" "F.Paste")
			(net "GND")
		)
		(pad "AE12" smd circle
			(at -4.499991 8.500008 180)
			(size 0.508 0.508)
			(layers "F.Cu" "F.Mask" "F.Paste")
			(net "GND")
		)
		(pad "AE13" smd circle
			(at -3.499993 8.500008 180)
			(size 0.508 0.508)
			(layers "F.Cu" "F.Mask" "F.Paste")
			(net "PCIE0_REFCLK_P")
		)
		(pad "AE14" smd circle
			(at -2.499995 8.500008 180)
			(size 0.508 0.508)
			(layers "F.Cu" "F.Mask" "F.Paste")
			(net "PCIE0_REFCLK_N")
		)
		(pad "AE15" smd circle
			(at -1.499997 8.500008 180)
			(size 0.508 0.508)
			(layers "F.Cu" "F.Mask" "F.Paste")
			(net "VDD_CORE")
		)
		(pad "AE16" smd circle
			(at -0.499999 8.500008 180)
			(size 0.508 0.508)
			(layers "F.Cu" "F.Mask" "F.Paste")
			(net "GND")
		)
		(pad "AE17" smd circle
			(at 0.499999 8.500008 180)
			(size 0.508 0.508)
			(layers "F.Cu" "F.Mask" "F.Paste")
			(net "VDD_CORE")
		)
		(pad "AE18" smd circle
			(at 1.499997 8.500008 180)
			(size 0.508 0.508)
			(layers "F.Cu" "F.Mask" "F.Paste")
			(net "GND")
		)
		(pad "AE19" smd circle
			(at 2.499995 8.500008 180)
			(size 0.508 0.508)
			(layers "F.Cu" "F.Mask" "F.Paste")
			(net "VDD_CORE")
		)
		(pad "AE20" smd circle
			(at 3.499993 8.500008 180)
			(size 0.508 0.508)
			(layers "F.Cu" "F.Mask" "F.Paste")
			(net "GND")
		)
		(pad "AE21" smd circle
			(at 4.499991 8.500008 180)
			(size 0.508 0.508)
			(layers "F.Cu" "F.Mask" "F.Paste")
			(net "VDD_CORE")
		)
		(pad "AE22" smd circle
			(at 5.499989 8.500008 180)
			(size 0.508 0.508)
			(layers "F.Cu" "F.Mask" "F.Paste")
			(net "VDDA_SERDES")
		)
		(pad "AE23" smd circle
			(at 6.500012 8.500008 180)
			(size 0.508 0.508)
			(layers "F.Cu" "F.Mask" "F.Paste")
			(net "VDDA_SERDES")
		)
		(pad "AE24" smd circle
			(at 7.50001 8.500008 180)
			(size 0.508 0.508)
			(layers "F.Cu" "F.Mask" "F.Paste")
			(net "VDDA_SERDES")
		)
		(pad "AE25" smd circle
			(at 8.500008 8.500008 180)
			(size 0.508 0.508)
			(layers "F.Cu" "F.Mask" "F.Paste")
			(net "NFP_SERDES012_SYSCLK_IN_P")
		)
		(pad "AE26" smd circle
			(at 9.500006 8.500008 180)
			(size 0.508 0.508)
			(layers "F.Cu" "F.Mask" "F.Paste")
			(net "NFP_SERDES012_SYSCLK_IN_N")
		)
		(pad "AE27" smd circle
			(at 10.500004 8.500008 180)
			(size 0.508 0.508)
			(layers "F.Cu" "F.Mask" "F.Paste")
			(net "GND")
		)
		(pad "AE28" smd circle
			(at 11.500002 8.500008 180)
			(size 0.508 0.508)
			(layers "F.Cu" "F.Mask" "F.Paste")
			(net "MUX_NFP_PCIE0_WAKE_L")
		)
		(pad "AE29" smd circle
			(at 12.5 8.500008 180)
			(size 0.508 0.508)
			(layers "F.Cu" "F.Mask" "F.Paste")
			(net "MUX_NFP_SMBUS_SDA")
		)
		(pad "AE30" smd circle
			(at 13.499998 8.500008 180)
			(size 0.508 0.508)
			(layers "F.Cu" "F.Mask" "F.Paste")
			(net "_NC_NFP_GPIO19")
		)
		(pad "AE31" smd circle
			(at 14.499996 8.500008 180)
			(size 0.508 0.508)
			(layers "F.Cu" "F.Mask" "F.Paste")
			(net "_NC_NFP_GPIO21")
		)
		(pad "AE32" smd circle
			(at 15.499994 8.500008 180)
			(size 0.508 0.508)
			(layers "F.Cu" "F.Mask" "F.Paste")
			(net "_NC_NFP_GPIO23")
		)
		(pad "AF1" smd circle
			(at -15.499994 9.500006 180)
			(size 0.508 0.508)
			(layers "F.Cu" "F.Mask" "F.Paste")
			(net "DDR0_32A_DQS0_P")
		)
		(pad "AF2" smd circle
			(at -14.499996 9.500006 180)
			(size 0.508 0.508)
			(layers "F.Cu" "F.Mask" "F.Paste")
			(net "DDR0_32A_DQ4")
		)
		(pad "AF3" smd circle
			(at -13.499998 9.500006 180)
			(size 0.508 0.508)
			(layers "F.Cu" "F.Mask" "F.Paste")
			(net "GND")
		)
		(pad "AF4" smd circle
			(at -12.5 9.500006 180)
			(size 0.508 0.508)
			(layers "F.Cu" "F.Mask" "F.Paste")
			(net "GND")
		)
		(pad "AF5" smd circle
			(at -11.500002 9.500006 180)
			(size 0.508 0.508)
			(layers "F.Cu" "F.Mask" "F.Paste")
			(net "_NC_NFP_PCIE1_APROBE1")
		)
		(pad "AF6" smd circle
			(at -10.500004 9.500006 180)
			(size 0.508 0.508)
			(layers "F.Cu" "F.Mask" "F.Paste")
			(net "GND")
		)
		(pad "AF7" smd circle
			(at -9.500006 9.500006 180)
			(size 0.508 0.508)
			(layers "F.Cu" "F.Mask" "F.Paste")
			(net "_NC_NFP_PCIE1_APROBE2")
		)
		(pad "AF8" smd circle
			(at -8.500008 9.500006 180)
			(size 0.508 0.508)
			(layers "F.Cu" "F.Mask" "F.Paste")
			(net "GND")
		)
		(pad "AF9" smd circle
			(at -7.50001 9.500006 180)
			(size 0.508 0.508)
			(layers "F.Cu" "F.Mask" "F.Paste")
			(net "GND")
		)
		(pad "AF10" smd circle
			(at -6.500012 9.500006 180)
			(size 0.508 0.508)
			(layers "F.Cu" "F.Mask" "F.Paste")
			(net "GND")
		)
		(pad "AF11" smd circle
			(at -5.499989 9.500006 180)
			(size 0.508 0.508)
			(layers "F.Cu" "F.Mask" "F.Paste")
			(net "GND")
		)
		(pad "AF12" smd circle
			(at -4.499991 9.500006 180)
			(size 0.508 0.508)
			(layers "F.Cu" "F.Mask" "F.Paste")
			(net "VDDA_PCIE0")
		)
		(pad "AF13" smd circle
			(at -3.499993 9.500006 180)
			(size 0.508 0.508)
			(layers "F.Cu" "F.Mask" "F.Paste")
			(net "VDDA_PCIE0")
		)
		(pad "AF14" smd circle
			(at -2.499995 9.500006 180)
			(size 0.508 0.508)
			(layers "F.Cu" "F.Mask" "F.Paste")
			(net "VDDA_PCIE0")
		)
		(pad "AF15" smd circle
			(at -1.499997 9.500006 180)
			(size 0.508 0.508)
			(layers "F.Cu" "F.Mask" "F.Paste")
			(net "_NC_NFP_PCIE0_APROBE1")
		)
		(pad "AF16" smd circle
			(at -0.499999 9.500006 180)
			(size 0.508 0.508)
			(layers "F.Cu" "F.Mask" "F.Paste")
			(net "VDDAH_PCIE0")
		)
		(pad "AF17" smd circle
			(at 0.499999 9.500006 180)
			(size 0.508 0.508)
			(layers "F.Cu" "F.Mask" "F.Paste")
			(net "_NC_NFP_PCIE0_APROBE2")
		)
		(pad "AF18" smd circle
			(at 1.499997 9.500006 180)
			(size 0.508 0.508)
			(layers "F.Cu" "F.Mask" "F.Paste")
			(net "GND")
		)
		(pad "AF19" smd circle
			(at 2.499995 9.500006 180)
			(size 0.508 0.508)
			(layers "F.Cu" "F.Mask" "F.Paste")
			(net "_NC_NFP_SERDES0_APROBE")
		)
		(pad "AF20" smd circle
			(at 3.499993 9.500006 180)
			(size 0.508 0.508)
			(layers "F.Cu" "F.Mask" "F.Paste")
			(net "VDDAH_SERDES")
		)
		(pad "AF21" smd circle
			(at 4.499991 9.500006 180)
			(size 0.508 0.508)
			(layers "F.Cu" "F.Mask" "F.Paste")
			(net "VDDAH_SERDES")
		)
		(pad "AF22" smd circle
			(at 5.499989 9.500006 180)
			(size 0.508 0.508)
			(layers "F.Cu" "F.Mask" "F.Paste")
			(net "VDDA_SERDES")
		)
		(pad "AF23" smd circle
			(at 6.500012 9.500006 180)
			(size 0.508 0.508)
			(layers "F.Cu" "F.Mask" "F.Paste")
			(net "VDDA_SERDES")
		)
		(pad "AF24" smd circle
			(at 7.50001 9.500006 180)
			(size 0.508 0.508)
			(layers "F.Cu" "F.Mask" "F.Paste")
			(net "GND")
		)
		(pad "AF25" smd circle
			(at 8.500008 9.500006 180)
			(size 0.508 0.508)
			(layers "F.Cu" "F.Mask" "F.Paste")
			(net "_NC_NFP_SERDES1_APROBE")
		)
		(pad "AF26" smd circle
			(at 9.500006 9.500006 180)
			(size 0.508 0.508)
			(layers "F.Cu" "F.Mask" "F.Paste")
			(net "GND")
		)
		(pad "AF27" smd circle
			(at 10.500004 9.500006 180)
			(size 0.508 0.508)
			(layers "F.Cu" "F.Mask" "F.Paste")
			(net "_NC_NFP_SERDES2_APROBE")
		)
		(pad "AF28" smd circle
			(at 11.500002 9.500006 180)
			(size 0.508 0.508)
			(layers "F.Cu" "F.Mask" "F.Paste")
			(net "VDD_1.2V")
		)
		(pad "AF29" smd circle
			(at 12.5 9.500006 180)
			(size 0.508 0.508)
			(layers "F.Cu" "F.Mask" "F.Paste")
			(net "VDD_1.2V")
		)
		(pad "AF30" smd circle
			(at 13.499998 9.500006 180)
			(size 0.508 0.508)
			(layers "F.Cu" "F.Mask" "F.Paste")
			(net "_NC_NFP_GPIO20")
		)
		(pad "AF31" smd circle
			(at 14.499996 9.500006 180)
			(size 0.508 0.508)
			(layers "F.Cu" "F.Mask" "F.Paste")
			(net "_NC_NFP_GPIO22")
		)
		(pad "AF32" smd circle
			(at 15.499994 9.500006 180)
			(size 0.508 0.508)
			(layers "F.Cu" "F.Mask" "F.Paste")
			(net "NFP_CORE_VID6")
		)
		(pad "AG1" smd circle
			(at -15.499994 10.500004 180)
			(size 0.508 0.508)
			(layers "F.Cu" "F.Mask" "F.Paste")
			(net "DDR0_32A_DQ7")
		)
		(pad "AG2" smd circle
			(at -14.499996 10.500004 180)
			(size 0.508 0.508)
			(layers "F.Cu" "F.Mask" "F.Paste")
			(net "DDR0_32A_DQ6")
		)
		(pad "AG3" smd circle
			(at -13.499998 10.500004 180)
			(size 0.508 0.508)
			(layers "F.Cu" "F.Mask" "F.Paste")
			(net "GND")
		)
		(pad "AG4" smd circle
			(at -12.5 10.500004 180)
			(size 0.508 0.508)
			(layers "F.Cu" "F.Mask" "F.Paste")
			(net "GND")
		)
		(pad "AG5" smd circle
			(at -11.500002 10.500004 180)
			(size 0.508 0.508)
			(layers "F.Cu" "F.Mask" "F.Paste")
			(net "GND")
		)
		(pad "AG6" smd circle
			(at -10.500004 10.500004 180)
			(size 0.508 0.508)
			(layers "F.Cu" "F.Mask" "F.Paste")
			(net "GND")
		)
		(pad "AG7" smd circle
			(at -9.500006 10.500004 180)
			(size 0.508 0.508)
			(layers "F.Cu" "F.Mask" "F.Paste")
			(net "GND")
		)
		(pad "AG8" smd circle
			(at -8.500008 10.500004 180)
			(size 0.508 0.508)
			(layers "F.Cu" "F.Mask" "F.Paste")
			(net "GND")
		)
		(pad "AG9" smd circle
			(at -7.50001 10.500004 180)
			(size 0.508 0.508)
			(layers "F.Cu" "F.Mask" "F.Paste")
			(net "GND")
		)
	)
)
